(kicad_pcb
	(version 20260206)
	(generator "pcbnew")
	(generator_version "10.0")
	(general
		(thickness 1.6)
		(legacy_teardrops no)
	)
	(paper "A4")
	(title_block
		(title "Wiwynn_Tioga_Pass_MB.brd")
		(comment 1 "Tioga Pass / footprints 3392-3397 of 4770")
	)
	(layers
		(0 "F.Cu" signal "TOP")
		(4 "In1.Cu" signal "L2GND")
		(6 "In2.Cu" signal "L3")
		(8 "In3.Cu" signal "L4GND")
		(10 "In4.Cu" signal "L5")
		(12 "In5.Cu" signal "L6GND")
		(14 "In6.Cu" signal "L7VCC")
		(16 "In7.Cu" signal "L8VCC")
		(18 "In8.Cu" signal "L9GND")
		(20 "In9.Cu" signal "L10")
		(22 "In10.Cu" signal "L11GND")
		(24 "In11.Cu" signal "L12")
		(26 "In12.Cu" signal "L13GND")
		(2 "B.Cu" signal "BOTTOM")
		(9 "F.Adhes" user "F.Adhesive")
		(11 "B.Adhes" user "B.Adhesive")
		(13 "F.Paste" user "Package Geometry/Pastemask Top")
		(15 "B.Paste" user "Package Geometry/Pastemask Bottom")
		(5 "F.SilkS" user "Ref Des/Silkscreen Top")
		(7 "B.SilkS" user "Ref Des/Silkscreen Bottom")
		(1 "F.Mask" user "Board Geometry/Soldermask Top")
		(3 "B.Mask" user "Board Geometry/Soldermask Bottom")
		(17 "Dwgs.User" user "User.Drawings")
		(19 "Cmts.User" user "User.Comments")
		(21 "Eco1.User" user "User.Eco1")
		(23 "Eco2.User" user "User.Eco2")
		(25 "Edge.Cuts" user "Board Geometry/Outline")
		(27 "Margin" user)
		(31 "F.CrtYd" user "Package Geometry/Place Bound Top")
		(29 "B.CrtYd" user "Package Geometry/Place Bound Bottom")
		(35 "F.Fab" user "Ref Des/Assembly Top")
		(33 "B.Fab" user "Ref Des/Assembly Bottom")
	)
	(footprint ""
		(layer "B.Cu")
		(at 438.5945 -15.92072)
		(property "Reference" "U9G1"
			(at -5.64388 -0.89027 0)
			(unlocked yes)
			(layer "B.SilkS")
			(effects
				(font
					(size 0.7874 0.5842)
					(thickness 0.1524)
				)
				(justify left mirror)
			)
		)
		(property "Value" ""
			(at 0 0 0)
			(layer "B.Fab")
			(effects
				(font
					(size 1.27 1.27)
				)
				(justify mirror)
			)
		)
		(duplicate_pad_numbers_are_jumpers no)
		(fp_line
			(start -4.4323 -0.64008)
			(end -4.4323 4.52628)
			(stroke
				(width 0.1524)
				(type default)
			)
			(layer "B.SilkS")
		)
		(fp_line
			(start -4.4323 4.52628)
			(end -1.5367 4.52628)
			(stroke
				(width 0.1524)
				(type default)
			)
			(layer "B.SilkS")
		)
		(fp_line
			(start -3.302 0.49022)
			(end -3.302 -0.64008)
			(stroke
				(width 0.1524)
				(type default)
			)
			(layer "B.SilkS")
		)
		(fp_line
			(start -2.667 -0.64008)
			(end -2.667 0.49022)
			(stroke
				(width 0.1524)
				(type default)
			)
			(layer "B.SilkS")
		)
		(fp_line
			(start -2.667 0.49022)
			(end -3.302 0.49022)
			(stroke
				(width 0.1524)
				(type default)
			)
			(layer "B.SilkS")
		)
		(fp_line
			(start -1.5367 -0.64008)
			(end -4.4323 -0.64008)
			(stroke
				(width 0.1524)
				(type default)
			)
			(layer "B.SilkS")
		)
		(fp_line
			(start -1.5367 4.52628)
			(end -1.5367 -0.64008)
			(stroke
				(width 0.1524)
				(type default)
			)
			(layer "B.SilkS")
		)
		(fp_circle
			(center 1.296162 -0.6731)
			(end 1.423162 -0.6731)
			(stroke
				(width 0.254)
				(type default)
			)
			(fill no)
			(layer "B.SilkS")
		)
		(fp_poly
			(pts
				(xy -0.7366 4.54152) (xy -0.7366 -0.64008) (xy -4.7244 -0.64008) (xy -5.2324 -0.64008) (xy -5.2324 4.54152)
				(xy -4.7244 4.54152)
			)
			(stroke
				(width 0)
				(type default)
			)
			(fill no)
			(layer "B.CrtYd")
		)
		(fp_line
			(start -5.2324 -0.64008)
			(end -5.2324 4.54152)
			(stroke
				(width 0.1)
				(type default)
			)
			(layer "B.Fab")
		)
		(fp_line
			(start -5.2324 4.54152)
			(end -0.7366 4.54152)
			(stroke
				(width 0.1)
				(type default)
			)
			(layer "B.Fab")
		)
		(fp_line
			(start -3.302 0.49022)
			(end -3.302 -0.64008)
			(stroke
				(width 0.1)
				(type default)
			)
			(layer "B.Fab")
		)
		(fp_line
			(start -2.667 -0.64008)
			(end -2.667 0.49022)
			(stroke
				(width 0.1)
				(type default)
			)
			(layer "B.Fab")
		)
		(fp_line
			(start -2.667 0.49022)
			(end -3.302 0.49022)
			(stroke
				(width 0.1)
				(type default)
			)
			(layer "B.Fab")
		)
		(fp_line
			(start -0.7366 -0.64008)
			(end -5.2324 -0.64008)
			(stroke
				(width 0.1)
				(type default)
			)
			(layer "B.Fab")
		)
		(fp_line
			(start -0.7366 4.54152)
			(end -0.7366 -0.64008)
			(stroke
				(width 0.1)
				(type default)
			)
			(layer "B.Fab")
		)
		(fp_circle
			(center 1.612138 -0.684784)
			(end 1.739138 -0.684784)
			(stroke
				(width 0.254)
				(type default)
			)
			(fill no)
			(layer "B.Fab")
		)
		(pad "1" smd rect
			(at 0 0 180)
			(size 2.159 0.381)
			(layers "B.Cu" "B.Mask" "B.Paste")
			(net "PD_DIR_2")
		)
		(pad "2" smd rect
			(at 0 0.65024 180)
			(size 2.159 0.381)
			(layers "B.Cu" "B.Mask" "B.Paste")
			(net "H_CPU1_MEMKLM_MEMHOT_G_R_N")
		)
		(pad "3" smd rect
			(at 0 1.30048 180)
			(size 2.159 0.381)
			(layers "B.Cu" "B.Mask" "B.Paste")
			(net "H_CPU1_MEMGHJ_MEMHOT_G_R_N")
		)
		(pad "4" smd rect
			(at 0 1.95072 180)
			(size 2.159 0.381)
			(layers "B.Cu" "B.Mask" "B.Paste")
			(net "P0V7_GTL2014_2")
		)
		(pad "5" smd rect
			(at 0 2.60096 180)
			(size 2.159 0.381)
			(layers "B.Cu" "B.Mask" "B.Paste")
			(net "H_CPU0_MEMDEF_MEMHOT_G_R_N")
		)
		(pad "6" smd rect
			(at 0 3.2512 180)
			(size 2.159 0.381)
			(layers "B.Cu" "B.Mask" "B.Paste")
			(net "H_CPU0_MEMABC_MEMHOT_G_R_N")
		)
		(pad "7" smd rect
			(at 0 3.90144 180)
			(size 2.159 0.381)
			(layers "B.Cu" "B.Mask" "B.Paste")
			(net "GND")
		)
		(pad "8" smd rect
			(at -5.969 3.90144 180)
			(size 2.159 0.381)
			(layers "B.Cu" "B.Mask" "B.Paste")
			(net "GND")
		)
		(pad "9" smd rect
			(at -5.969 3.2512 180)
			(size 2.159 0.381)
			(layers "B.Cu" "B.Mask" "B.Paste")
			(net "H_CPU0_ABC_MEMHOT_LVT3_R_N")
		)
		(pad "10" smd rect
			(at -5.969 2.60096 180)
			(size 2.159 0.381)
			(layers "B.Cu" "B.Mask" "B.Paste")
			(net "H_CPU0_DEF_MEMHOT_LVT3_R_N")
		)
		(pad "11" smd rect
			(at -5.969 1.95072 180)
			(size 2.159 0.381)
			(layers "B.Cu" "B.Mask" "B.Paste")
			(net "GND")
		)
		(pad "12" smd rect
			(at -5.969 1.30048 180)
			(size 2.159 0.381)
			(layers "B.Cu" "B.Mask" "B.Paste")
			(net "H_CPU1_GHJ_MEMHOT_LVT3_R_N")
		)
		(pad "13" smd rect
			(at -5.969 0.65024 180)
			(size 2.159 0.381)
			(layers "B.Cu" "B.Mask" "B.Paste")
			(net "H_CPU1_KLM_MEMHOT_LVT3_R_N")
		)
		(pad "14" smd rect
			(at -5.969 0 180)
			(size 2.159 0.381)
			(layers "B.Cu" "B.Mask" "B.Paste")
			(net "P3V3")
		)
	)
	(footprint ""
		(layer "B.Cu")
		(at 428.3075 -21.844 -90)
		(property "Reference" "R25W129"
			(at 0.8382 -0.67818 270)
			(unlocked yes)
			(layer "B.SilkS")
			(effects
				(font
					(size 0.4064 0.254)
					(thickness 0.1524)
				)
				(justify left mirror)
			)
		)
		(property "Value" ""
			(at 0 0 90)
			(layer "B.Fab")
			(effects
				(font
					(size 1.27 1.27)
				)
				(justify mirror)
			)
		)
		(duplicate_pad_numbers_are_jumpers no)
		(fp_poly
			(pts
				(xy 0.2794 -0.1016) (xy -0.2794 -0.1016) (xy -0.2794 0.9906) (xy 0.2794 0.9906)
			)
			(stroke
				(width 0)
				(type default)
			)
			(fill no)
			(layer "B.CrtYd")
		)
		(fp_line
			(start -0.2794 0.9906)
			(end -0.2794 -0.1016)
			(stroke
				(width 0.1)
				(type default)
			)
			(layer "B.Fab")
		)
		(fp_line
			(start 0.2794 0.9906)
			(end -0.2794 0.9906)
			(stroke
				(width 0.1)
				(type default)
			)
			(layer "B.Fab")
		)
		(fp_line
			(start -0.2794 -0.1016)
			(end 0.2794 -0.1016)
			(stroke
				(width 0.1)
				(type default)
			)
			(layer "B.Fab")
		)
		(fp_line
			(start 0.2794 -0.1016)
			(end 0.2794 0.9906)
			(stroke
				(width 0.1)
				(type default)
			)
			(layer "B.Fab")
		)
		(pad "1" smd rect
			(at 0 0 90)
			(size 0.508 0.508)
			(layers "B.Cu" "B.Mask" "B.Paste")
			(net "P3V3")
		)
		(pad "2" smd rect
			(at 0 0.889 90)
			(size 0.508 0.508)
			(layers "B.Cu" "B.Mask" "B.Paste")
			(net "I2C_BMC_VGA_DDC_SCL")
		)
		(zone
			(layer "B.Cu")
			(hatch none 0.5)
			(connect_pads
				(clearance 0)
			)
			(min_thickness 0.25)
			(keepout
				(tracks not_allowed)
				(vias allowed)
				(pads allowed)
				(copperpour not_allowed)
				(footprints allowed)
			)
			(placement
				(enabled no)
				(sheetname "")
			)
			(fill
				(thermal_gap 0.5)
				(thermal_bridge_width 0.5)
				(island_removal_mode 0)
			)
			(polygon
				(pts
					(xy 427.6725 -21.59) (xy 427.6725 -22.098) (xy 428.0535 -22.098) (xy 428.0535 -21.59)
				)
			)
		)
		(zone
			(layer "B.Cu")
			(hatch none 0.5)
			(connect_pads
				(clearance 0)
			)
			(min_thickness 0.25)
			(keepout
				(tracks allowed)
				(vias not_allowed)
				(pads allowed)
				(copperpour not_allowed)
				(footprints allowed)
			)
			(placement
				(enabled no)
				(sheetname "")
			)
			(fill
				(thermal_gap 0.5)
				(thermal_bridge_width 0.5)
				(island_removal_mode 0)
			)
			(polygon
				(pts
					(xy 428.0535 -21.59) (xy 428.0535 -22.098) (xy 427.6725 -22.098) (xy 427.6725 -21.59)
				)
			)
		)
	)
	(footprint ""
		(layer "B.Cu")
		(at 490.203998 -35.445192 180)
		(property "Reference" "U9F1"
			(at -3.03276 3.60553 180)
			(unlocked yes)
			(layer "B.SilkS")
			(effects
				(font
					(size 0.7874 0.5842)
					(thickness 0.1524)
				)
				(justify mirror)
			)
		)
		(property "Value" ""
			(at 0 0 0)
			(layer "B.Fab")
			(effects
				(font
					(size 1.27 1.27)
				)
				(justify mirror)
			)
		)
		(duplicate_pad_numbers_are_jumpers no)
		(fp_line
			(start -1.269238 1.8034)
			(end -1.77673 1.8034)
			(stroke
				(width 0.1524)
				(type default)
			)
			(layer "B.SilkS")
		)
		(fp_line
			(start -1.269238 -0.3048)
			(end -1.77673 -0.3048)
			(stroke
				(width 0.1524)
				(type default)
			)
			(layer "B.SilkS")
		)
		(fp_circle
			(center -0.149606 -0.7366)
			(end -0.276606 -0.7366)
			(stroke
				(width 0.635)
				(type default)
			)
			(fill no)
			(layer "B.SilkS")
		)
		(fp_rect
			(start -0.3302 1.8034)
			(end -2.7432 -0.3048)
			(stroke
				(width 0)
				(type default)
			)
			(fill no)
			(layer "B.CrtYd")
		)
		(fp_line
			(start -0.3302 1.8034)
			(end -0.3302 -0.3048)
			(stroke
				(width 0.1)
				(type default)
			)
			(layer "B.Fab")
		)
		(fp_line
			(start -0.3302 -0.3048)
			(end -2.7432 -0.3048)
			(stroke
				(width 0.1)
				(type default)
			)
			(layer "B.Fab")
		)
		(fp_line
			(start -2.7432 1.8034)
			(end -0.3302 1.8034)
			(stroke
				(width 0.1)
				(type default)
			)
			(layer "B.Fab")
		)
		(fp_line
			(start -2.7432 -0.3048)
			(end -2.7432 1.8034)
			(stroke
				(width 0.1)
				(type default)
			)
			(layer "B.Fab")
		)
		(fp_circle
			(center -0.149606 -0.7366)
			(end -0.276606 -0.7366)
			(stroke
				(width 0.254)
				(type default)
			)
			(fill no)
			(layer "B.Fab")
		)
		(pad "1" smd rect
			(at 0 0)
			(size 1.524 0.254)
			(layers "B.Cu" "B.Mask" "B.Paste")
			(net "SP2_BMC_CM_UART_RX_R")
		)
		(pad "2" smd rect
			(at 0 0.499872)
			(size 1.524 0.254)
			(layers "B.Cu" "B.Mask" "B.Paste")
			(net "UART_BMC_RXD5")
		)
		(pad "3" smd rect
			(at 0 0.999744)
			(size 1.524 0.254)
			(layers "B.Cu" "B.Mask" "B.Paste")
			(net "SP1_BMC_HOST_UART_RX")
		)
		(pad "4" smd rect
			(at 0 1.499616)
			(size 1.524 0.254)
			(layers "B.Cu" "B.Mask" "B.Paste")
			(net "GND")
		)
		(pad "5" smd rect
			(at -3.048 1.499616)
			(size 1.524 0.254)
			(layers "B.Cu" "B.Mask" "B.Paste")
			(net "FM_UARTSW_MSB_N")
		)
		(pad "6" smd rect
			(at -3.048 0.999744)
			(size 1.524 0.254)
			(layers "B.Cu" "B.Mask" "B.Paste")
			(net "FM_UARTSW_LSB_N")
		)
		(pad "7" smd rect
			(at -3.048 0.499872)
			(size 1.524 0.254)
			(layers "B.Cu" "B.Mask" "B.Paste")
			(net "UART_MUX_IN_R")
		)
		(pad "8" smd rect
			(at -3.048 0)
			(size 1.524 0.254)
			(layers "B.Cu" "B.Mask" "B.Paste")
			(net "P3V3_STBY")
		)
	)
	(footprint ""
		(layer "B.Cu")
		(at 422.3004 -13.335)
		(property "Reference" "R2T5"
			(at 0 0 0)
			(layer "B.SilkS")
			(hide yes)
			(effects
				(font
					(size 1.27 1.27)
				)
				(justify mirror)
			)
		)
		(property "Value" ""
			(at 0 0 0)
			(layer "B.Fab")
			(effects
				(font
					(size 1.27 1.27)
				)
				(justify mirror)
			)
		)
		(duplicate_pad_numbers_are_jumpers no)
		(fp_poly
			(pts
				(xy 0.2794 -0.1016) (xy -0.2794 -0.1016) (xy -0.2794 0.9906) (xy 0.2794 0.9906)
			)
			(stroke
				(width 0)
				(type default)
			)
			(fill no)
			(layer "B.CrtYd")
		)
		(fp_line
			(start -0.2794 -0.1016)
			(end 0.2794 -0.1016)
			(stroke
				(width 0.1)
				(type default)
			)
			(layer "B.Fab")
		)
		(fp_line
			(start -0.2794 0.9906)
			(end -0.2794 -0.1016)
			(stroke
				(width 0.1)
				(type default)
			)
			(layer "B.Fab")
		)
		(fp_line
			(start 0.2794 -0.1016)
			(end 0.2794 0.9906)
			(stroke
				(width 0.1)
				(type default)
			)
			(layer "B.Fab")
		)
		(fp_line
			(start 0.2794 0.9906)
			(end -0.2794 0.9906)
			(stroke
				(width 0.1)
				(type default)
			)
			(layer "B.Fab")
		)
		(pad "1" smd rect
			(at 0 0 180)
			(size 0.508 0.508)
			(layers "B.Cu" "B.Mask" "B.Paste")
			(net "P3V3_STBY")
		)
		(pad "2" smd rect
			(at 0 0.889 180)
			(size 0.508 0.508)
			(layers "B.Cu" "B.Mask" "B.Paste")
			(net "H_CPU0_FAST_WAKE")
		)
		(zone
			(layer "B.Cu")
			(hatch none 0.5)
			(connect_pads
				(clearance 0)
			)
			(min_thickness 0.25)
			(keepout
				(tracks allowed)
				(vias not_allowed)
				(pads allowed)
				(copperpour not_allowed)
				(footprints allowed)
			)
			(placement
				(enabled no)
				(sheetname "")
			)
			(fill
				(thermal_gap 0.5)
				(thermal_bridge_width 0.5)
				(island_removal_mode 0)
			)
			(polygon
				(pts
					(xy 422.5544 -13.081) (xy 422.0464 -13.081) (xy 422.0464 -12.7) (xy 422.5544 -12.7)
				)
			)
		)
		(zone
			(layer "B.Cu")
			(hatch none 0.5)
			(connect_pads
				(clearance 0)
			)
			(min_thickness 0.25)
			(keepout
				(tracks not_allowed)
				(vias allowed)
				(pads allowed)
				(copperpour not_allowed)
				(footprints allowed)
			)
			(placement
				(enabled no)
				(sheetname "")
			)
			(fill
				(thermal_gap 0.5)
				(thermal_bridge_width 0.5)
				(island_removal_mode 0)
			)
			(polygon
				(pts
					(xy 422.5544 -12.7) (xy 422.0464 -12.7) (xy 422.0464 -13.081) (xy 422.5544 -13.081)
				)
			)
		)
	)
	(footprint ""
		(layer "B.Cu")
		(at 411.5435 -33.401 -90)
		(property "Reference" "C25W48"
			(at 0.8382 -0.67818 270)
			(unlocked yes)
			(layer "B.SilkS")
			(effects
				(font
					(size 0.4064 0.254)
					(thickness 0.1524)
				)
				(justify left mirror)
			)
		)
		(property "Value" ""
			(at 0 0 90)
			(layer "B.Fab")
			(effects
				(font
					(size 1.27 1.27)
				)
				(justify mirror)
			)
		)
		(duplicate_pad_numbers_are_jumpers no)
		(fp_poly
			(pts
				(xy -0.3048 -0.1016) (xy -0.3048 0.9906) (xy 0.3048 0.9906) (xy 0.3048 -0.1016)
			)
			(stroke
				(width 0)
				(type default)
			)
			(fill no)
			(layer "B.CrtYd")
		)
		(fp_line
			(start -0.3048 0.9906)
			(end -0.3048 -0.1016)
			(stroke
				(width 0.1)
				(type default)
			)
			(layer "B.Fab")
		)
		(fp_line
			(start 0.3048 0.9906)
			(end -0.3048 0.9906)
			(stroke
				(width 0.1)
				(type default)
			)
			(layer "B.Fab")
		)
		(fp_line
			(start -0.3048 -0.1016)
			(end 0.3048 -0.1016)
			(stroke
				(width 0.1)
				(type default)
			)
			(layer "B.Fab")
		)
		(fp_line
			(start 0.3048 -0.1016)
			(end 0.3048 0.9906)
			(stroke
				(width 0.1)
				(type default)
			)
			(layer "B.Fab")
		)
		(pad "1" smd rect
			(at 0 0 90)
			(size 0.508 0.508)
			(layers "B.Cu" "B.Mask" "B.Paste")
			(net "P3V3_STBY")
		)
		(pad "2" smd rect
			(at 0 0.889 90)
			(size 0.508 0.508)
			(layers "B.Cu" "B.Mask" "B.Paste")
			(net "GND")
		)
		(zone
			(layer "B.Cu")
			(hatch none 0.5)
			(connect_pads
				(clearance 0)
			)
			(min_thickness 0.25)
			(keepout
				(tracks not_allowed)
				(vias allowed)
				(pads allowed)
				(copperpour not_allowed)
				(footprints allowed)
			)
			(placement
				(enabled no)
				(sheetname "")
			)
			(fill
				(thermal_gap 0.5)
				(thermal_bridge_width 0.5)
				(island_removal_mode 0)
			)
			(polygon
				(pts
					(xy 410.9085 -33.147) (xy 410.9085 -33.655) (xy 411.2895 -33.655) (xy 411.2895 -33.147)
				)
			)
		)
		(zone
			(layer "B.Cu")
			(hatch none 0.5)
			(connect_pads
				(clearance 0)
			)
			(min_thickness 0.25)
			(keepout
				(tracks allowed)
				(vias not_allowed)
				(pads allowed)
				(copperpour not_allowed)
				(footprints allowed)
			)
			(placement
				(enabled no)
				(sheetname "")
			)
			(fill
				(thermal_gap 0.5)
				(thermal_bridge_width 0.5)
				(island_removal_mode 0)
			)
			(polygon
				(pts
					(xy 411.2895 -33.147) (xy 411.2895 -33.655) (xy 410.9085 -33.655) (xy 410.9085 -33.147)
				)
			)
		)
	)
	(footprint ""
		(layer "B.Cu")
		(at 482.512116 -142.485872 -90)
		(property "Reference" "R6W4"
			(at 0.8382 -0.67818 270)
			(unlocked yes)
			(layer "B.SilkS")
			(effects
				(font
					(size 0.4064 0.254)
					(thickness 0.1524)
				)
				(justify left mirror)
			)
		)
		(property "Value" ""
			(at 0 0 90)
			(layer "B.Fab")
			(effects
				(font
					(size 1.27 1.27)
				)
				(justify mirror)
			)
		)
		(duplicate_pad_numbers_are_jumpers no)
		(fp_poly
			(pts
				(xy 0.2794 -0.1016) (xy -0.2794 -0.1016) (xy -0.2794 0.9906) (xy 0.2794 0.9906)
			)
			(stroke
				(width 0)
				(type default)
			)
			(fill no)
			(layer "B.CrtYd")
		)
		(fp_line
			(start -0.2794 0.9906)
			(end -0.2794 -0.1016)
			(stroke
				(width 0.1)
				(type default)
			)
			(layer "B.Fab")
		)
		(fp_line
			(start 0.2794 0.9906)
			(end -0.2794 0.9906)
			(stroke
				(width 0.1)
				(type default)
			)
			(layer "B.Fab")
		)
		(fp_line
			(start -0.2794 -0.1016)
			(end 0.2794 -0.1016)
			(stroke
				(width 0.1)
				(type default)
			)
			(layer "B.Fab")
		)
		(fp_line
			(start 0.2794 -0.1016)
			(end 0.2794 0.9906)
			(stroke
				(width 0.1)
				(type default)
			)
			(layer "B.Fab")
		)
		(pad "1" smd rect
			(at 0 0 90)
			(size 0.508 0.508)
			(layers "B.Cu" "B.Mask" "B.Paste")
			(net "P3V3_STBY")
		)
		(pad "2" smd rect
			(at 0 0.889 90)
			(size 0.508 0.508)
			(layers "B.Cu" "B.Mask" "B.Paste")
			(net "PCA9555_A2")
		)
		(zone
			(layer "B.Cu")
			(hatch none 0.5)
			(connect_pads
				(clearance 0)
			)
			(min_thickness 0.25)
			(keepout
				(tracks not_allowed)
				(vias allowed)
				(pads allowed)
				(copperpour not_allowed)
				(footprints allowed)
			)
			(placement
				(enabled no)
				(sheetname "")
			)
			(fill
				(thermal_gap 0.5)
				(thermal_bridge_width 0.5)
				(island_removal_mode 0)
			)
			(polygon
				(pts
					(xy 481.877116 -142.231872) (xy 481.877116 -142.739872) (xy 482.258116 -142.739872) (xy 482.258116 -142.231872)
				)
			)
		)
		(zone
			(layer "B.Cu")
			(hatch none 0.5)
			(connect_pads
				(clearance 0)
			)
			(min_thickness 0.25)
			(keepout
				(tracks allowed)
				(vias not_allowed)
				(pads allowed)
				(copperpour not_allowed)
				(footprints allowed)
			)
			(placement
				(enabled no)
				(sheetname "")
			)
			(fill
				(thermal_gap 0.5)
				(thermal_bridge_width 0.5)
				(island_removal_mode 0)
			)
			(polygon
				(pts
					(xy 482.258116 -142.231872) (xy 482.258116 -142.739872) (xy 481.877116 -142.739872) (xy 481.877116 -142.231872)
				)
			)
		)
	)
)
